(kicad_pcb
	(version 20260206)
	(generator "pcbnew")
	(generator_version "10.0")
	(general
		(thickness 1.6)
		(legacy_teardrops no)
	)
	(paper "A4")
	(title_block
		(title "Bryce Canyon_F.DPB_16315-1-OCP.brd")
		(comment 1 "Bryce Canyon / footprints 423-429 of 2223")
	)
	(layers
		(0 "F.Cu" signal "TOP")
		(4 "In1.Cu" signal "L2GND")
		(6 "In2.Cu" signal "L3")
		(8 "In3.Cu" signal "L4GND")
		(10 "In4.Cu" signal "L5")
		(12 "In5.Cu" signal "L6VCC")
		(14 "In6.Cu" signal "L7VCC")
		(16 "In7.Cu" signal "L8")
		(18 "In8.Cu" signal "L9GND")
		(20 "In9.Cu" signal "L10")
		(22 "In10.Cu" signal "L11GND")
		(2 "B.Cu" signal "BOTTOM")
		(9 "F.Adhes" user "F.Adhesive")
		(11 "B.Adhes" user "B.Adhesive")
		(13 "F.Paste" user "Package Geometry/Pastemask Top")
		(15 "B.Paste" user "Package Geometry/Pastemask Bottom")
		(5 "F.SilkS" user "Ref Des/Silkscreen Top")
		(7 "B.SilkS" user "Ref Des/Silkscreen Bottom")
		(1 "F.Mask" user "Board Geometry/Soldermask Top")
		(3 "B.Mask" user "Board Geometry/Soldermask Bottom")
		(17 "Dwgs.User" user "User.Drawings")
		(19 "Cmts.User" user "User.Comments")
		(21 "Eco1.User" user "User.Eco1")
		(23 "Eco2.User" user "User.Eco2")
		(25 "Edge.Cuts" user "Board Geometry/Outline")
		(27 "Margin" user)
		(31 "F.CrtYd" user "Package Geometry/Place Bound Top")
		(29 "B.CrtYd" user "Package Geometry/Place Bound Bottom")
		(35 "F.Fab" user "Ref Des/Assembly Top")
		(33 "B.Fab" user "Ref Des/Assembly Bottom")
	)
	(footprint ""
		(layer "F.Cu")
		(at 190.213488 -44.219368 90)
		(property "Reference" "C415"
			(at 0 0 90)
			(layer "F.SilkS")
			(hide yes)
			(effects
				(font
					(size 1.27 1.27)
				)
			)
		)
		(property "Value" "SCD01U16V1KX-GP"
			(at -2.8321 -1.7399 90)
			(unlocked yes)
			(layer "F.Fab")
			(hide yes)
			(effects
				(font
					(size 1.016 1.016)
					(thickness 0.1524)
				)
			)
		)
		(property "Device Type" "C0201H13"
			(at -2.8321 -3.2639 90)
			(unlocked yes)
			(layer "F.Fab")
			(hide yes)
			(effects
				(font
					(size 1.016 1.016)
					(thickness 0.1524)
				)
			)
		)
		(duplicate_pad_numbers_are_jumpers no)
		(fp_rect
			(start -0.2794 0.6477)
			(end 0.2794 -0.6477)
			(stroke
				(width 0)
				(type default)
			)
			(fill no)
			(layer "F.CrtYd")
		)
		(fp_rect
			(start -0.2794 0.6477)
			(end 0.2794 -0.6477)
			(stroke
				(width 0)
				(type default)
			)
			(fill no)
			(layer "F.Fab")
		)
		(pad "1" smd custom
			(at 0 -0.2794 90)
			(size 0.0762 0.0762)
			(layers "F.Cu" "F.Mask" "F.Paste")
			(net "SAS_HDD_RX_N29")
			(options
				(clearance outline)
				(anchor circle)
			)
			(primitives
				(gr_poly
					(pts
						(arc
							(start 0.1524 -0.127)
							(mid 0.137521 -0.162921)
							(end 0.1016 -0.1778)
						)
						(arc
							(start -0.1016 -0.1778)
							(mid -0.137521 -0.162921)
							(end -0.1524 -0.127)
						)
						(arc
							(start -0.1524 0.127)
							(mid -0.137521 0.162921)
							(end -0.1016 0.1778)
						)
						(arc
							(start 0.1016 0.1778)
							(mid 0.137521 0.162921)
							(end 0.1524 0.127)
						)
					)
					(width 0)
					(fill yes)
				)
			)
		)
		(pad "2" smd custom
			(at 0 0.2794 90)
			(size 0.0762 0.0762)
			(layers "F.Cu" "F.Mask" "F.Paste")
			(net "PHY_SCC_A_TO_DRV_A_29_DN")
			(options
				(clearance outline)
				(anchor circle)
			)
			(primitives
				(gr_poly
					(pts
						(arc
							(start 0.1524 -0.127)
							(mid 0.137521 -0.162921)
							(end 0.1016 -0.1778)
						)
						(arc
							(start -0.1016 -0.1778)
							(mid -0.137521 -0.162921)
							(end -0.1524 -0.127)
						)
						(arc
							(start -0.1524 0.127)
							(mid -0.137521 0.162921)
							(end -0.1016 0.1778)
						)
						(arc
							(start 0.1016 0.1778)
							(mid 0.137521 0.162921)
							(end 0.1524 0.127)
						)
					)
					(width 0)
					(fill yes)
				)
			)
		)
	)
	(footprint ""
		(layer "F.Cu")
		(at 466.4456 -294.3098 180)
		(property "Reference" "R333"
			(at 0 0 180)
			(layer "F.SilkS")
			(hide yes)
			(effects
				(font
					(size 1.27 1.27)
				)
			)
		)
		(property "Value" "91R3F-1-GP"
			(at -0.0254 -2.5146 180)
			(unlocked yes)
			(layer "F.Fab")
			(hide yes)
			(effects
				(font
					(size 1.016 1.016)
					(thickness 0.1524)
				)
			)
		)
		(property "Device Type" "R603H22"
			(at -0.0254 -4.0386 180)
			(unlocked yes)
			(layer "F.Fab")
			(hide yes)
			(effects
				(font
					(size 1.016 1.016)
					(thickness 0.1524)
				)
			)
		)
		(duplicate_pad_numbers_are_jumpers no)
		(fp_line
			(start 0.2032 0)
			(end 0.4826 0)
			(stroke
				(width 0.2032)
				(type default)
			)
			(layer "F.SilkS")
		)
		(fp_line
			(start -0.4826 0)
			(end -0.2032 0)
			(stroke
				(width 0.2032)
				(type default)
			)
			(layer "F.SilkS")
		)
		(fp_rect
			(start -0.5842 1.3335)
			(end 0.5842 -1.3335)
			(stroke
				(width 0)
				(type default)
			)
			(fill no)
			(layer "F.CrtYd")
		)
		(fp_rect
			(start -0.5842 1.3335)
			(end 0.5842 -1.3335)
			(stroke
				(width 0)
				(type default)
			)
			(fill no)
			(layer "F.Fab")
		)
		(pad "1" smd custom
			(at 0 -0.762 180)
			(size 0.2159 0.2159)
			(layers "F.Cu" "F.Mask" "F.Paste")
			(net "P5V_B")
			(options
				(clearance outline)
				(anchor circle)
			)
			(primitives
				(gr_poly
					(pts
						(arc
							(start -0.3302 -0.4318)
							(mid -0.402042 -0.402042)
							(end -0.4318 -0.3302)
						)
						(arc
							(start -0.4318 0.3302)
							(mid -0.402042 0.402042)
							(end -0.3302 0.4318)
						)
						(arc
							(start 0.3302 0.4318)
							(mid 0.402042 0.402042)
							(end 0.4318 0.3302)
						)
						(arc
							(start 0.4318 -0.3302)
							(mid 0.402042 -0.402042)
							(end 0.3302 -0.4318)
						)
					)
					(width 0)
					(fill yes)
				)
			)
		)
		(pad "2" smd custom
			(at 0 0.762 180)
			(size 0.2159 0.2159)
			(layers "F.Cu" "F.Mask" "F.Paste")
			(net "DRV_ACT_35")
			(options
				(clearance outline)
				(anchor circle)
			)
			(primitives
				(gr_poly
					(pts
						(arc
							(start -0.3302 -0.4318)
							(mid -0.402042 -0.402042)
							(end -0.4318 -0.3302)
						)
						(arc
							(start -0.4318 0.3302)
							(mid -0.402042 0.402042)
							(end -0.3302 0.4318)
						)
						(arc
							(start 0.3302 0.4318)
							(mid 0.402042 0.402042)
							(end 0.4318 0.3302)
						)
						(arc
							(start 0.4318 -0.3302)
							(mid 0.402042 -0.402042)
							(end 0.3302 -0.4318)
						)
					)
					(width 0)
					(fill yes)
				)
			)
		)
	)
	(footprint ""
		(layer "F.Cu")
		(at 255.481328 11.049 -90)
		(property "Reference" "R634"
			(at 0 0 270)
			(layer "F.SilkS")
			(hide yes)
			(effects
				(font
					(size 1.27 1.27)
				)
			)
		)
		(property "Value" "10KR2F-2-GP"
			(at 0.064008 -3.993896 270)
			(unlocked yes)
			(layer "F.Fab")
			(hide yes)
			(effects
				(font
					(size 1.016 1.016)
					(thickness 0.1524)
				)
			)
		)
		(property "Device Type" "R402H16"
			(at 0.064008 -5.517896 270)
			(unlocked yes)
			(layer "F.Fab")
			(hide yes)
			(effects
				(font
					(size 1.016 1.016)
					(thickness 0.1524)
				)
			)
		)
		(duplicate_pad_numbers_are_jumpers no)
		(fp_line
			(start -0.508 -0.9398)
			(end -0.508 0.9398)
			(stroke
				(width 0.1524)
				(type default)
			)
			(layer "F.SilkS")
		)
		(fp_line
			(start 0.508 -0.9398)
			(end -0.508 -0.9398)
			(stroke
				(width 0.1524)
				(type default)
			)
			(layer "F.SilkS")
		)
		(fp_rect
			(start -0.508 0.9398)
			(end 0.508 -0.9398)
			(stroke
				(width 0)
				(type default)
			)
			(fill no)
			(layer "F.CrtYd")
		)
		(fp_rect
			(start -0.508 0.9398)
			(end 0.508 -0.9398)
			(stroke
				(width 0)
				(type default)
			)
			(fill no)
			(layer "F.Fab")
		)
		(pad "1" smd custom
			(at 0 -0.4445 270)
			(size 0.1397 0.1397)
			(layers "F.Cu" "F.Mask" "F.Paste")
			(net "P3V3_STBY_A")
			(options
				(clearance outline)
				(anchor circle)
			)
			(primitives
				(gr_poly
					(pts
						(arc
							(start -0.1778 -0.2794)
							(mid -0.249642 -0.249642)
							(end -0.2794 -0.1778)
						)
						(arc
							(start -0.2794 0.1778)
							(mid -0.249642 0.249642)
							(end -0.1778 0.2794)
						)
						(arc
							(start 0.1778 0.2794)
							(mid 0.249642 0.249642)
							(end 0.2794 0.1778)
						)
						(arc
							(start 0.2794 -0.1778)
							(mid 0.249642 -0.249642)
							(end 0.1778 -0.2794)
						)
					)
					(width 0)
					(fill yes)
				)
			)
		)
		(pad "2" smd custom
			(at 0 0.4445 270)
			(size 0.1397 0.1397)
			(layers "F.Cu" "F.Mask" "F.Paste")
			(net "IOM_A_PWR_LED")
			(options
				(clearance outline)
				(anchor circle)
			)
			(primitives
				(gr_poly
					(pts
						(arc
							(start -0.1778 -0.2794)
							(mid -0.249642 -0.249642)
							(end -0.2794 -0.1778)
						)
						(arc
							(start -0.2794 0.1778)
							(mid -0.249642 0.249642)
							(end -0.1778 0.2794)
						)
						(arc
							(start 0.1778 0.2794)
							(mid 0.249642 0.249642)
							(end 0.2794 0.1778)
						)
						(arc
							(start 0.2794 -0.1778)
							(mid 0.249642 -0.249642)
							(end 0.1778 -0.2794)
						)
					)
					(width 0)
					(fill yes)
				)
			)
		)
	)
	(footprint ""
		(layer "F.Cu")
		(at 36.178998 -180.064918 90)
		(property "Reference" "R410"
			(at 0 0 90)
			(layer "F.SilkS")
			(hide yes)
			(effects
				(font
					(size 1.27 1.27)
				)
			)
		)
		(property "Value" "220R3F-1-GP"
			(at -0.0254 -2.5146 90)
			(unlocked yes)
			(layer "F.Fab")
			(hide yes)
			(effects
				(font
					(size 1.016 1.016)
					(thickness 0.1524)
				)
			)
		)
		(property "Device Type" "R603H22"
			(at -0.0254 -4.0386 90)
			(unlocked yes)
			(layer "F.Fab")
			(hide yes)
			(effects
				(font
					(size 1.016 1.016)
					(thickness 0.1524)
				)
			)
		)
		(duplicate_pad_numbers_are_jumpers no)
		(fp_line
			(start 0.2032 0)
			(end 0.4826 0)
			(stroke
				(width 0.2032)
				(type default)
			)
			(layer "F.SilkS")
		)
		(fp_line
			(start -0.4826 0)
			(end -0.2032 0)
			(stroke
				(width 0.2032)
				(type default)
			)
			(layer "F.SilkS")
		)
		(fp_rect
			(start -0.5842 1.3335)
			(end 0.5842 -1.3335)
			(stroke
				(width 0)
				(type default)
			)
			(fill no)
			(layer "F.CrtYd")
		)
		(fp_rect
			(start -0.5842 1.3335)
			(end 0.5842 -1.3335)
			(stroke
				(width 0)
				(type default)
			)
			(fill no)
			(layer "F.Fab")
		)
		(pad "1" smd custom
			(at 0 -0.762 90)
			(size 0.2159 0.2159)
			(layers "F.Cu" "F.Mask" "F.Paste")
			(net "HDD_PRSNT_12")
			(options
				(clearance outline)
				(anchor circle)
			)
			(primitives
				(gr_poly
					(pts
						(arc
							(start -0.3302 -0.4318)
							(mid -0.402042 -0.402042)
							(end -0.4318 -0.3302)
						)
						(arc
							(start -0.4318 0.3302)
							(mid -0.402042 0.402042)
							(end -0.3302 0.4318)
						)
						(arc
							(start 0.3302 0.4318)
							(mid 0.402042 0.402042)
							(end 0.4318 0.3302)
						)
						(arc
							(start 0.4318 -0.3302)
							(mid 0.402042 -0.402042)
							(end 0.3302 -0.4318)
						)
					)
					(width 0)
					(fill yes)
				)
			)
		)
		(pad "2" smd custom
			(at 0 0.762 90)
			(size 0.2159 0.2159)
			(layers "F.Cu" "F.Mask" "F.Paste")
			(net "DRIVE_A_12_INS")
			(options
				(clearance outline)
				(anchor circle)
			)
			(primitives
				(gr_poly
					(pts
						(arc
							(start -0.3302 -0.4318)
							(mid -0.402042 -0.402042)
							(end -0.4318 -0.3302)
						)
						(arc
							(start -0.4318 0.3302)
							(mid -0.402042 0.402042)
							(end -0.3302 0.4318)
						)
						(arc
							(start 0.3302 0.4318)
							(mid 0.402042 0.402042)
							(end 0.4318 0.3302)
						)
						(arc
							(start 0.4318 -0.3302)
							(mid 0.402042 -0.402042)
							(end 0.3302 -0.4318)
						)
					)
					(width 0)
					(fill yes)
				)
			)
		)
	)
	(footprint ""
		(layer "F.Cu")
		(at 190.213488 -158.660592 90)
		(property "Reference" "C260"
			(at 0 0 90)
			(layer "F.SilkS")
			(hide yes)
			(effects
				(font
					(size 1.27 1.27)
				)
			)
		)
		(property "Value" "SCD01U16V1KX-GP"
			(at -2.8321 -1.7399 90)
			(unlocked yes)
			(layer "F.Fab")
			(hide yes)
			(effects
				(font
					(size 1.016 1.016)
					(thickness 0.1524)
				)
			)
		)
		(property "Device Type" "C0201H13"
			(at -2.8321 -3.2639 90)
			(unlocked yes)
			(layer "F.Fab")
			(hide yes)
			(effects
				(font
					(size 1.016 1.016)
					(thickness 0.1524)
				)
			)
		)
		(duplicate_pad_numbers_are_jumpers no)
		(fp_rect
			(start -0.2794 0.6477)
			(end 0.2794 -0.6477)
			(stroke
				(width 0)
				(type default)
			)
			(fill no)
			(layer "F.CrtYd")
		)
		(fp_rect
			(start -0.2794 0.6477)
			(end 0.2794 -0.6477)
			(stroke
				(width 0)
				(type default)
			)
			(fill no)
			(layer "F.Fab")
		)
		(pad "1" smd custom
			(at 0 -0.2794 90)
			(size 0.0762 0.0762)
			(layers "F.Cu" "F.Mask" "F.Paste")
			(net "SAS_HDD_RX_P17")
			(options
				(clearance outline)
				(anchor circle)
			)
			(primitives
				(gr_poly
					(pts
						(arc
							(start 0.1524 -0.127)
							(mid 0.137521 -0.162921)
							(end 0.1016 -0.1778)
						)
						(arc
							(start -0.1016 -0.1778)
							(mid -0.137521 -0.162921)
							(end -0.1524 -0.127)
						)
						(arc
							(start -0.1524 0.127)
							(mid -0.137521 0.162921)
							(end -0.1016 0.1778)
						)
						(arc
							(start 0.1016 0.1778)
							(mid 0.137521 0.162921)
							(end 0.1524 0.127)
						)
					)
					(width 0)
					(fill yes)
				)
			)
		)
		(pad "2" smd custom
			(at 0 0.2794 90)
			(size 0.0762 0.0762)
			(layers "F.Cu" "F.Mask" "F.Paste")
			(net "PHY_SCC_A_TO_DRV_A_17_DP")
			(options
				(clearance outline)
				(anchor circle)
			)
			(primitives
				(gr_poly
					(pts
						(arc
							(start 0.1524 -0.127)
							(mid 0.137521 -0.162921)
							(end 0.1016 -0.1778)
						)
						(arc
							(start -0.1016 -0.1778)
							(mid -0.137521 -0.162921)
							(end -0.1524 -0.127)
						)
						(arc
							(start -0.1524 0.127)
							(mid -0.137521 0.162921)
							(end -0.1016 0.1778)
						)
						(arc
							(start 0.1016 0.1778)
							(mid 0.137521 0.162921)
							(end 0.1524 0.127)
						)
					)
					(width 0)
					(fill yes)
				)
			)
		)
	)
	(footprint ""
		(layer "F.Cu")
		(at 409.800044 -324.39991)
		(property "Reference" "RLED34"
			(at 0 0 0)
			(layer "F.SilkS")
			(hide yes)
			(effects
				(font
					(size 1.27 1.27)
				)
			)
		)
		(property "Value" "LED-BY-19-GP"
			(at -2.132076 1.414018 0)
			(unlocked yes)
			(layer "F.Fab")
			(hide yes)
			(effects
				(font
					(size 1.016 1.016)
					(thickness 0.1524)
				)
			)
		)
		(property "Device Type" "LED-1615-4PH26"
			(at -2.132076 -0.109982 0)
			(unlocked yes)
			(layer "F.Fab")
			(hide yes)
			(effects
				(font
					(size 1.016 1.016)
					(thickness 0.1524)
				)
			)
		)
		(duplicate_pad_numbers_are_jumpers no)
		(fp_line
			(start -1.2954 0.254)
			(end -1.2954 1.6002)
			(stroke
				(width 0.508)
				(type default)
			)
			(layer "F.SilkS")
		)
		(fp_line
			(start -1.2954 1.6002)
			(end 1.2954 1.6002)
			(stroke
				(width 0.508)
				(type default)
			)
			(layer "F.SilkS")
		)
		(fp_line
			(start -1.1176 -1.4224)
			(end 1.1176 -1.4224)
			(stroke
				(width 0.1524)
				(type default)
			)
			(layer "F.SilkS")
		)
		(fp_line
			(start -1.1176 1.4224)
			(end -1.1176 -1.4224)
			(stroke
				(width 0.1524)
				(type default)
			)
			(layer "F.SilkS")
		)
		(fp_line
			(start 1.1176 -1.4224)
			(end 1.1176 1.4224)
			(stroke
				(width 0.1524)
				(type default)
			)
			(layer "F.SilkS")
		)
		(fp_line
			(start 1.1176 1.4224)
			(end -1.1176 1.4224)
			(stroke
				(width 0.1524)
				(type default)
			)
			(layer "F.SilkS")
		)
		(fp_line
			(start 1.2954 1.6002)
			(end 1.2954 0.254)
			(stroke
				(width 0.508)
				(type default)
			)
			(layer "F.SilkS")
		)
		(fp_rect
			(start -0.7493 0.8001)
			(end 0.7493 -0.8001)
			(stroke
				(width 0)
				(type default)
			)
			(fill no)
			(layer "F.CrtYd")
		)
		(fp_poly
			(pts
				(xy -1.3716 1.6764) (xy -1.3716 -1.6764) (xy 1.3716 -1.6764) (xy 1.3716 0.0635) (xy 0.7493 0.0635)
				(xy 0.7493 -0.8001) (xy -0.7493 -0.8001) (xy -0.7493 0.8001) (xy 0.7493 0.8001) (xy 0.7493 0.0762)
				(xy 1.3716 0.0762) (xy 1.3716 1.6764)
			)
			(stroke
				(width 0)
				(type default)
			)
			(fill no)
			(layer "F.CrtYd")
		)
		(fp_rect
			(start -1.3716 1.6764)
			(end 1.3716 -1.6764)
			(stroke
				(width 0)
				(type default)
			)
			(fill no)
			(layer "F.Fab")
		)
		(pad "1" smd rect
			(at 0.50038 -0.73025)
			(size 0.7112 0.8636)
			(layers "F.Cu" "F.Mask" "F.Paste")
			(net "DRV_ACT_33")
		)
		(pad "2" smd rect
			(at -0.50038 -0.73025)
			(size 0.7112 0.8636)
			(layers "F.Cu" "F.Mask" "F.Paste")
			(net "FLT_HDD33")
		)
		(pad "3" smd rect
			(at 0.50038 0.73025)
			(size 0.7112 0.8636)
			(layers "F.Cu" "F.Mask" "F.Paste")
			(net "DRV_ACT_33_N")
		)
		(pad "4" smd rect
			(at -0.50038 0.73025)
			(size 0.7112 0.8636)
			(layers "F.Cu" "F.Mask" "F.Paste")
			(net "FLT_HDD33_N")
		)
	)
	(footprint ""
		(layer "F.Cu")
		(at 79.924148 -282.085542 90)
		(property "Reference" "R183"
			(at 0 0 90)
			(layer "F.SilkS")
			(hide yes)
			(effects
				(font
					(size 1.27 1.27)
				)
			)
		)
		(property "Value" "4K7R2J-2-GP"
			(at 0.064008 -3.993896 90)
			(unlocked yes)
			(layer "F.Fab")
			(hide yes)
			(effects
				(font
					(size 1.016 1.016)
					(thickness 0.1524)
				)
			)
		)
		(property "Device Type" "R402H16"
			(at 0.064008 -5.517896 90)
			(unlocked yes)
			(layer "F.Fab")
			(hide yes)
			(effects
				(font
					(size 1.016 1.016)
					(thickness 0.1524)
				)
			)
		)
		(duplicate_pad_numbers_are_jumpers no)
		(fp_line
			(start 0.508 -0.9398)
			(end -0.508 -0.9398)
			(stroke
				(width 0.1524)
				(type default)
			)
			(layer "F.SilkS")
		)
		(fp_line
			(start -0.508 -0.9398)
			(end -0.508 0.9398)
			(stroke
				(width 0.1524)
				(type default)
			)
			(layer "F.SilkS")
		)
		(fp_rect
			(start -0.508 0.9398)
			(end 0.508 -0.9398)
			(stroke
				(width 0)
				(type default)
			)
			(fill no)
			(layer "F.CrtYd")
		)
		(fp_rect
			(start -0.508 0.9398)
			(end 0.508 -0.9398)
			(stroke
				(width 0)
				(type default)
			)
			(fill no)
			(layer "F.Fab")
		)
		(pad "1" smd custom
			(at 0 -0.4445 90)
			(size 0.1397 0.1397)
			(layers "F.Cu" "F.Mask" "F.Paste")
			(net "P12V_A")
			(options
				(clearance outline)
				(anchor circle)
			)
			(primitives
				(gr_poly
					(pts
						(arc
							(start -0.1778 -0.2794)
							(mid -0.249642 -0.249642)
							(end -0.2794 -0.1778)
						)
						(arc
							(start -0.2794 0.1778)
							(mid -0.249642 0.249642)
							(end -0.1778 0.2794)
						)
						(arc
							(start 0.1778 0.2794)
							(mid 0.249642 0.249642)
							(end 0.2794 0.1778)
						)
						(arc
							(start 0.2794 -0.1778)
							(mid 0.249642 -0.249642)
							(end 0.1778 -0.2794)
						)
					)
					(width 0)
					(fill yes)
				)
			)
		)
		(pad "2" smd custom
			(at 0 0.4445 90)
			(size 0.1397 0.1397)
			(layers "F.Cu" "F.Mask" "F.Paste")
			(net "SW_HDD_P2")
			(options
				(clearance outline)
				(anchor circle)
			)
			(primitives
				(gr_poly
					(pts
						(arc
							(start -0.1778 -0.2794)
							(mid -0.249642 -0.249642)
							(end -0.2794 -0.1778)
						)
						(arc
							(start -0.2794 0.1778)
							(mid -0.249642 0.249642)
							(end -0.1778 0.2794)
						)
						(arc
							(start 0.1778 0.2794)
							(mid 0.249642 0.249642)
							(end 0.2794 0.1778)
						)
						(arc
							(start 0.2794 -0.1778)
							(mid 0.249642 -0.249642)
							(end 0.1778 -0.2794)
						)
					)
					(width 0)
					(fill yes)
				)
			)
		)
	)
)
